(kicad_pcb
	(version 20260206)
	(generator "pcbnew")
	(generator_version "10.0")
	(general
		(thickness 1.6)
		(legacy_teardrops no)
	)
	(paper "A4")
	(title_block
		(title "Bryce Canyon_IOM_IOC_16318-2_OCP.brd")
		(comment 1 "Bryce Canyon / footprints 1312-1320 of 1605")
	)
	(layers
		(0 "F.Cu" signal "TOP")
		(4 "In1.Cu" signal "L2GND")
		(6 "In2.Cu" signal "L3")
		(8 "In3.Cu" signal "L4VCC")
		(10 "In4.Cu" signal "L5VCC")
		(12 "In5.Cu" signal "L6")
		(14 "In6.Cu" signal "L7GND")
		(2 "B.Cu" signal "BOTTOM")
		(9 "F.Adhes" user "F.Adhesive")
		(11 "B.Adhes" user "B.Adhesive")
		(13 "F.Paste" user "Package Geometry/Pastemask Top")
		(15 "B.Paste" user "Package Geometry/Pastemask Bottom")
		(5 "F.SilkS" user "Ref Des/Silkscreen Top")
		(7 "B.SilkS" user "Ref Des/Silkscreen Bottom")
		(1 "F.Mask" user "Board Geometry/Soldermask Top")
		(3 "B.Mask" user "Board Geometry/Soldermask Bottom")
		(17 "Dwgs.User" user "User.Drawings")
		(19 "Cmts.User" user "User.Comments")
		(21 "Eco1.User" user "User.Eco1")
		(23 "Eco2.User" user "User.Eco2")
		(25 "Edge.Cuts" user "Board Geometry/Outline")
		(27 "Margin" user)
		(31 "F.CrtYd" user "Package Geometry/Place Bound Top")
		(29 "B.CrtYd" user "Package Geometry/Place Bound Bottom")
		(35 "F.Fab" user "Ref Des/Assembly Top")
		(33 "B.Fab" user "Ref Des/Assembly Bottom")
	)
	(footprint ""
		(layer "B.Cu")
		(at 38.113716 -149.555708 -90)
		(property "Reference" "R318"
			(at 0 0 90)
			(layer "B.SilkS")
			(hide yes)
			(effects
				(font
					(size 1.27 1.27)
				)
				(justify mirror)
			)
		)
		(property "Value" "0R2J-2-GP"
			(at -0.064008 -3.993896 270)
			(unlocked yes)
			(layer "B.Fab")
			(hide yes)
			(effects
				(font
					(size 1.016 1.016)
					(thickness 0.1524)
				)
				(justify mirror)
			)
		)
		(property "Device Type" "R402H16"
			(at -0.064008 -5.517896 270)
			(unlocked yes)
			(layer "B.Fab")
			(hide yes)
			(effects
				(font
					(size 1.016 1.016)
					(thickness 0.1524)
				)
				(justify mirror)
			)
		)
		(duplicate_pad_numbers_are_jumpers no)
		(fp_line
			(start -0.508 -0.9398)
			(end 0.508 -0.9398)
			(stroke
				(width 0.1524)
				(type default)
			)
			(layer "B.SilkS")
		)
		(fp_line
			(start 0.508 -0.9398)
			(end 0.508 0.9398)
			(stroke
				(width 0.1524)
				(type default)
			)
			(layer "B.SilkS")
		)
		(fp_rect
			(start 0.508 0.9398)
			(end -0.508 -0.9398)
			(stroke
				(width 0)
				(type default)
			)
			(fill no)
			(layer "B.CrtYd")
		)
		(fp_rect
			(start 0.508 0.9398)
			(end -0.508 -0.9398)
			(stroke
				(width 0)
				(type default)
			)
			(fill no)
			(layer "B.Fab")
		)
		(pad "1" smd custom
			(at 0 -0.4445 90)
			(size 0.1397 0.1397)
			(layers "B.Cu" "B.Mask" "B.Paste")
			(net "COMP_PWR_EN_R")
			(options
				(clearance outline)
				(anchor circle)
			)
			(primitives
				(gr_poly
					(pts
						(arc
							(start -0.1778 0.2794)
							(mid -0.249642 0.249642)
							(end -0.2794 0.1778)
						)
						(arc
							(start -0.2794 -0.1778)
							(mid -0.249642 -0.249642)
							(end -0.1778 -0.2794)
						)
						(arc
							(start 0.1778 -0.2794)
							(mid 0.249642 -0.249642)
							(end 0.2794 -0.1778)
						)
						(arc
							(start 0.2794 0.1778)
							(mid 0.249642 0.249642)
							(end 0.1778 0.2794)
						)
					)
					(width 0)
					(fill yes)
				)
			)
		)
		(pad "2" smd custom
			(at 0 0.4445 90)
			(size 0.1397 0.1397)
			(layers "B.Cu" "B.Mask" "B.Paste")
			(net "COMP_PWR_EN")
			(options
				(clearance outline)
				(anchor circle)
			)
			(primitives
				(gr_poly
					(pts
						(arc
							(start -0.1778 0.2794)
							(mid -0.249642 0.249642)
							(end -0.2794 0.1778)
						)
						(arc
							(start -0.2794 -0.1778)
							(mid -0.249642 -0.249642)
							(end -0.1778 -0.2794)
						)
						(arc
							(start 0.1778 -0.2794)
							(mid 0.249642 -0.249642)
							(end 0.2794 -0.1778)
						)
						(arc
							(start 0.2794 0.1778)
							(mid 0.249642 0.249642)
							(end 0.1778 0.2794)
						)
					)
					(width 0)
					(fill yes)
				)
			)
		)
	)
	(footprint ""
		(layer "B.Cu")
		(at 12.11199 -142.463266 90)
		(property "Reference" "R212"
			(at 0 0 90)
			(layer "B.SilkS")
			(hide yes)
			(effects
				(font
					(size 1.27 1.27)
				)
				(justify mirror)
			)
		)
		(property "Value" "120R2F-GP"
			(at -0.064008 -3.993896 90)
			(unlocked yes)
			(layer "B.Fab")
			(hide yes)
			(effects
				(font
					(size 1.016 1.016)
					(thickness 0.1524)
				)
				(justify mirror)
			)
		)
		(property "Device Type" "R402H16"
			(at -0.064008 -5.517896 90)
			(unlocked yes)
			(layer "B.Fab")
			(hide yes)
			(effects
				(font
					(size 1.016 1.016)
					(thickness 0.1524)
				)
				(justify mirror)
			)
		)
		(duplicate_pad_numbers_are_jumpers no)
		(fp_line
			(start 0.508 -0.9398)
			(end 0.508 0.9398)
			(stroke
				(width 0.1524)
				(type default)
			)
			(layer "B.SilkS")
		)
		(fp_line
			(start -0.508 -0.9398)
			(end 0.508 -0.9398)
			(stroke
				(width 0.1524)
				(type default)
			)
			(layer "B.SilkS")
		)
		(fp_rect
			(start 0.508 0.9398)
			(end -0.508 -0.9398)
			(stroke
				(width 0)
				(type default)
			)
			(fill no)
			(layer "B.CrtYd")
		)
		(fp_rect
			(start 0.508 0.9398)
			(end -0.508 -0.9398)
			(stroke
				(width 0)
				(type default)
			)
			(fill no)
			(layer "B.Fab")
		)
		(pad "1" smd custom
			(at 0 -0.4445 270)
			(size 0.1397 0.1397)
			(layers "B.Cu" "B.Mask" "B.Paste")
			(net "MEMODT")
			(options
				(clearance outline)
				(anchor circle)
			)
			(primitives
				(gr_poly
					(pts
						(arc
							(start -0.1778 0.2794)
							(mid -0.249642 0.249642)
							(end -0.2794 0.1778)
						)
						(arc
							(start -0.2794 -0.1778)
							(mid -0.249642 -0.249642)
							(end -0.1778 -0.2794)
						)
						(arc
							(start 0.1778 -0.2794)
							(mid 0.249642 -0.249642)
							(end 0.2794 -0.1778)
						)
						(arc
							(start 0.2794 0.1778)
							(mid 0.249642 0.249642)
							(end 0.1778 0.2794)
						)
					)
					(width 0)
					(fill yes)
				)
			)
		)
		(pad "2" smd custom
			(at 0 0.4445 270)
			(size 0.1397 0.1397)
			(layers "B.Cu" "B.Mask" "B.Paste")
			(net "P1V2_STBY")
			(options
				(clearance outline)
				(anchor circle)
			)
			(primitives
				(gr_poly
					(pts
						(arc
							(start -0.1778 0.2794)
							(mid -0.249642 0.249642)
							(end -0.2794 0.1778)
						)
						(arc
							(start -0.2794 -0.1778)
							(mid -0.249642 -0.249642)
							(end -0.1778 -0.2794)
						)
						(arc
							(start 0.1778 -0.2794)
							(mid 0.249642 -0.249642)
							(end 0.2794 -0.1778)
						)
						(arc
							(start 0.2794 0.1778)
							(mid 0.249642 0.249642)
							(end 0.1778 0.2794)
						)
					)
					(width 0)
					(fill yes)
				)
			)
		)
	)
	(footprint ""
		(layer "B.Cu")
		(at 55.575454 -145.058384 90)
		(property "Reference" "TP83"
			(at 0 0 90)
			(layer "B.SilkS")
			(hide yes)
			(effects
				(font
					(size 1.27 1.27)
				)
				(justify mirror)
			)
		)
		(property "Value" "TPAD28-2-GP"
			(at 0.0127 -1.6637 90)
			(unlocked yes)
			(layer "B.Fab")
			(hide yes)
			(effects
				(font
					(size 1.016 1.016)
					(thickness 0.1524)
				)
				(justify mirror)
			)
		)
		(property "Device Type" "TPAD28"
			(at 0.0127 -3.1877 90)
			(unlocked yes)
			(layer "B.Fab")
			(hide yes)
			(effects
				(font
					(size 1.016 1.016)
					(thickness 0.1524)
				)
				(justify mirror)
			)
		)
		(duplicate_pad_numbers_are_jumpers no)
		(fp_poly
			(pts
				(arc
					(start 0 0.3556)
					(mid 0 -0.3556)
					(end 0 0.3556)
				)
			)
			(stroke
				(width 0)
				(type default)
			)
			(fill no)
			(layer "B.CrtYd")
		)
		(fp_poly
			(pts
				(arc
					(start 0 0.6096)
					(mid 0 -0.6096)
					(end 0 0.6096)
				)
			)
			(stroke
				(width 0)
				(type default)
			)
			(fill no)
			(layer "B.Fab")
		)
		(pad "1" smd circle
			(at 0 0 270)
			(size 0.7112 0.7112)
			(layers "B.Cu" "B.Mask" "B.Paste")
			(net "JTAG_BMC_TDO")
		)
	)
	(footprint ""
		(layer "B.Cu")
		(at 95.874078 -176.581562 -90)
		(property "Reference" "R100"
			(at 0 0 90)
			(layer "B.SilkS")
			(hide yes)
			(effects
				(font
					(size 1.27 1.27)
				)
				(justify mirror)
			)
		)
		(property "Value" "0R2J-2-GP"
			(at -0.064008 -3.993896 270)
			(unlocked yes)
			(layer "B.Fab")
			(hide yes)
			(effects
				(font
					(size 1.016 1.016)
					(thickness 0.1524)
				)
				(justify mirror)
			)
		)
		(property "Device Type" "R402H16"
			(at -0.064008 -5.517896 270)
			(unlocked yes)
			(layer "B.Fab")
			(hide yes)
			(effects
				(font
					(size 1.016 1.016)
					(thickness 0.1524)
				)
				(justify mirror)
			)
		)
		(duplicate_pad_numbers_are_jumpers no)
		(fp_line
			(start -0.508 -0.9398)
			(end 0.508 -0.9398)
			(stroke
				(width 0.1524)
				(type default)
			)
			(layer "B.SilkS")
		)
		(fp_line
			(start 0.508 -0.9398)
			(end 0.508 0.9398)
			(stroke
				(width 0.1524)
				(type default)
			)
			(layer "B.SilkS")
		)
		(fp_rect
			(start 0.508 0.9398)
			(end -0.508 -0.9398)
			(stroke
				(width 0)
				(type default)
			)
			(fill no)
			(layer "B.CrtYd")
		)
		(fp_rect
			(start 0.508 0.9398)
			(end -0.508 -0.9398)
			(stroke
				(width 0)
				(type default)
			)
			(fill no)
			(layer "B.Fab")
		)
		(pad "1" smd custom
			(at 0 -0.4445 90)
			(size 0.1397 0.1397)
			(layers "B.Cu" "B.Mask" "B.Paste")
			(net "I2C_BMC_COMP_ALERT_N_R")
			(options
				(clearance outline)
				(anchor circle)
			)
			(primitives
				(gr_poly
					(pts
						(arc
							(start -0.1778 0.2794)
							(mid -0.249642 0.249642)
							(end -0.2794 0.1778)
						)
						(arc
							(start -0.2794 -0.1778)
							(mid -0.249642 -0.249642)
							(end -0.1778 -0.2794)
						)
						(arc
							(start 0.1778 -0.2794)
							(mid 0.249642 -0.249642)
							(end 0.2794 -0.1778)
						)
						(arc
							(start 0.2794 0.1778)
							(mid 0.249642 0.249642)
							(end 0.1778 0.2794)
						)
					)
					(width 0)
					(fill yes)
				)
			)
		)
		(pad "2" smd custom
			(at 0 0.4445 90)
			(size 0.1397 0.1397)
			(layers "B.Cu" "B.Mask" "B.Paste")
			(net "I2C_BMC_COMP_ALERT_N")
			(options
				(clearance outline)
				(anchor circle)
			)
			(primitives
				(gr_poly
					(pts
						(arc
							(start -0.1778 0.2794)
							(mid -0.249642 0.249642)
							(end -0.2794 0.1778)
						)
						(arc
							(start -0.2794 -0.1778)
							(mid -0.249642 -0.249642)
							(end -0.1778 -0.2794)
						)
						(arc
							(start 0.1778 -0.2794)
							(mid 0.249642 -0.249642)
							(end 0.2794 -0.1778)
						)
						(arc
							(start 0.2794 0.1778)
							(mid 0.249642 0.249642)
							(end 0.1778 0.2794)
						)
					)
					(width 0)
					(fill yes)
				)
			)
		)
	)
	(footprint ""
		(layer "B.Cu")
		(at 54.229 -161.163 90)
		(property "Reference" "R404"
			(at 0 0 90)
			(layer "B.SilkS")
			(hide yes)
			(effects
				(font
					(size 1.27 1.27)
				)
				(justify mirror)
			)
		)
		(property "Value" "1KR2F-3-GP"
			(at -0.064008 -3.993896 90)
			(unlocked yes)
			(layer "B.Fab")
			(hide yes)
			(effects
				(font
					(size 1.016 1.016)
					(thickness 0.1524)
				)
				(justify mirror)
			)
		)
		(property "Device Type" "R402H16"
			(at -0.064008 -5.517896 90)
			(unlocked yes)
			(layer "B.Fab")
			(hide yes)
			(effects
				(font
					(size 1.016 1.016)
					(thickness 0.1524)
				)
				(justify mirror)
			)
		)
		(duplicate_pad_numbers_are_jumpers no)
		(fp_line
			(start 0.508 -0.9398)
			(end 0.508 0.9398)
			(stroke
				(width 0.1524)
				(type default)
			)
			(layer "B.SilkS")
		)
		(fp_line
			(start -0.508 -0.9398)
			(end 0.508 -0.9398)
			(stroke
				(width 0.1524)
				(type default)
			)
			(layer "B.SilkS")
		)
		(fp_rect
			(start 0.508 0.9398)
			(end -0.508 -0.9398)
			(stroke
				(width 0)
				(type default)
			)
			(fill no)
			(layer "B.CrtYd")
		)
		(fp_rect
			(start 0.508 0.9398)
			(end -0.508 -0.9398)
			(stroke
				(width 0)
				(type default)
			)
			(fill no)
			(layer "B.Fab")
		)
		(pad "1" smd custom
			(at 0 -0.4445 270)
			(size 0.1397 0.1397)
			(layers "B.Cu" "B.Mask" "B.Paste")
			(net "ADC_12V")
			(options
				(clearance outline)
				(anchor circle)
			)
			(primitives
				(gr_poly
					(pts
						(arc
							(start -0.1778 0.2794)
							(mid -0.249642 0.249642)
							(end -0.2794 0.1778)
						)
						(arc
							(start -0.2794 -0.1778)
							(mid -0.249642 -0.249642)
							(end -0.1778 -0.2794)
						)
						(arc
							(start 0.1778 -0.2794)
							(mid 0.249642 -0.249642)
							(end 0.2794 -0.1778)
						)
						(arc
							(start 0.2794 0.1778)
							(mid 0.249642 0.249642)
							(end 0.1778 0.2794)
						)
					)
					(width 0)
					(fill yes)
				)
			)
		)
		(pad "2" smd custom
			(at 0 0.4445 270)
			(size 0.1397 0.1397)
			(layers "B.Cu" "B.Mask" "B.Paste")
			(net "GND")
			(options
				(clearance outline)
				(anchor circle)
			)
			(primitives
				(gr_poly
					(pts
						(arc
							(start -0.1778 0.2794)
							(mid -0.249642 0.249642)
							(end -0.2794 0.1778)
						)
						(arc
							(start -0.2794 -0.1778)
							(mid -0.249642 -0.249642)
							(end -0.1778 -0.2794)
						)
						(arc
							(start 0.1778 -0.2794)
							(mid 0.249642 -0.249642)
							(end 0.2794 -0.1778)
						)
						(arc
							(start 0.2794 0.1778)
							(mid 0.249642 0.249642)
							(end 0.1778 0.2794)
						)
					)
					(width 0)
					(fill yes)
				)
			)
		)
	)
	(footprint ""
		(layer "B.Cu")
		(at 45.2374 -139.3698)
		(property "Reference" "TP21"
			(at 0 0 0)
			(layer "B.SilkS")
			(hide yes)
			(effects
				(font
					(size 1.27 1.27)
				)
				(justify mirror)
			)
		)
		(property "Value" "TPAD28-2-GP"
			(at 0.0127 -1.6637 0)
			(unlocked yes)
			(layer "B.Fab")
			(hide yes)
			(effects
				(font
					(size 1.016 1.016)
					(thickness 0.1524)
				)
				(justify mirror)
			)
		)
		(property "Device Type" "TPAD28"
			(at 0.0127 -3.1877 0)
			(unlocked yes)
			(layer "B.Fab")
			(hide yes)
			(effects
				(font
					(size 1.016 1.016)
					(thickness 0.1524)
				)
				(justify mirror)
			)
		)
		(duplicate_pad_numbers_are_jumpers no)
		(fp_poly
			(pts
				(arc
					(start 0.3556 0)
					(mid -0.3556 0)
					(end 0.3556 0)
				)
			)
			(stroke
				(width 0)
				(type default)
			)
			(fill no)
			(layer "B.CrtYd")
		)
		(fp_poly
			(pts
				(arc
					(start 0.6096 0)
					(mid -0.6096 0)
					(end 0.6096 0)
				)
			)
			(stroke
				(width 0)
				(type default)
			)
			(fill no)
			(layer "B.Fab")
		)
		(pad "1" smd circle
			(at 0 0 180)
			(size 0.7112 0.7112)
			(layers "B.Cu" "B.Mask" "B.Paste")
			(net "TP_M2_2_ALERT#")
		)
	)
	(footprint ""
		(layer "B.Cu")
		(at 191.68999 -21.844 -90)
		(property "Reference" "C486"
			(at 0 0 90)
			(layer "B.SilkS")
			(hide yes)
			(effects
				(font
					(size 1.27 1.27)
				)
				(justify mirror)
			)
		)
		(property "Value" "SCD01U16V1KX-GP"
			(at 2.8321 -1.7399 270)
			(unlocked yes)
			(layer "B.Fab")
			(hide yes)
			(effects
				(font
					(size 1.016 1.016)
					(thickness 0.1524)
				)
				(justify mirror)
			)
		)
		(property "Device Type" "C0201H13"
			(at 2.8321 -3.2639 270)
			(unlocked yes)
			(layer "B.Fab")
			(hide yes)
			(effects
				(font
					(size 1.016 1.016)
					(thickness 0.1524)
				)
				(justify mirror)
			)
		)
		(duplicate_pad_numbers_are_jumpers no)
		(fp_rect
			(start 0.2794 0.6477)
			(end -0.2794 -0.6477)
			(stroke
				(width 0)
				(type default)
			)
			(fill no)
			(layer "B.CrtYd")
		)
		(fp_rect
			(start 0.2794 0.6477)
			(end -0.2794 -0.6477)
			(stroke
				(width 0)
				(type default)
			)
			(fill no)
			(layer "B.Fab")
		)
		(pad "1" smd custom
			(at 0 -0.2794 90)
			(size 0.0762 0.0762)
			(layers "B.Cu" "B.Mask" "B.Paste")
			(net "PHY_CON_A_TO_IOC_1_DP")
			(options
				(clearance outline)
				(anchor circle)
			)
			(primitives
				(gr_poly
					(pts
						(arc
							(start 0.1524 0.127)
							(mid 0.137521 0.162921)
							(end 0.1016 0.1778)
						)
						(arc
							(start -0.1016 0.1778)
							(mid -0.137521 0.162921)
							(end -0.1524 0.127)
						)
						(arc
							(start -0.1524 -0.127)
							(mid -0.137521 -0.162921)
							(end -0.1016 -0.1778)
						)
						(arc
							(start 0.1016 -0.1778)
							(mid 0.137521 -0.162921)
							(end 0.1524 -0.127)
						)
					)
					(width 0)
					(fill yes)
				)
			)
		)
		(pad "2" smd custom
			(at 0 0.2794 90)
			(size 0.0762 0.0762)
			(layers "B.Cu" "B.Mask" "B.Paste")
			(net "PHY_CON_A_TO_IOC_1_DP_C")
			(options
				(clearance outline)
				(anchor circle)
			)
			(primitives
				(gr_poly
					(pts
						(arc
							(start 0.1524 0.127)
							(mid 0.137521 0.162921)
							(end 0.1016 0.1778)
						)
						(arc
							(start -0.1016 0.1778)
							(mid -0.137521 0.162921)
							(end -0.1524 0.127)
						)
						(arc
							(start -0.1524 -0.127)
							(mid -0.137521 -0.162921)
							(end -0.1016 -0.1778)
						)
						(arc
							(start 0.1016 -0.1778)
							(mid 0.137521 -0.162921)
							(end 0.1524 -0.127)
						)
					)
					(width 0)
					(fill yes)
				)
			)
		)
	)
	(footprint ""
		(layer "B.Cu")
		(at 42.418 -131.7752 180)
		(property "Reference" "R284"
			(at 0 0 0)
			(layer "B.SilkS")
			(hide yes)
			(effects
				(font
					(size 1.27 1.27)
				)
				(justify mirror)
			)
		)
		(property "Value" "33R2F-3-GP"
			(at -0.064008 -3.993896 180)
			(unlocked yes)
			(layer "B.Fab")
			(hide yes)
			(effects
				(font
					(size 1.016 1.016)
					(thickness 0.1524)
				)
				(justify mirror)
			)
		)
		(property "Device Type" "R402H16"
			(at -0.064008 -5.517896 180)
			(unlocked yes)
			(layer "B.Fab")
			(hide yes)
			(effects
				(font
					(size 1.016 1.016)
					(thickness 0.1524)
				)
				(justify mirror)
			)
		)
		(duplicate_pad_numbers_are_jumpers no)
		(fp_line
			(start 0.508 -0.9398)
			(end 0.508 0.9398)
			(stroke
				(width 0.1524)
				(type default)
			)
			(layer "B.SilkS")
		)
		(fp_line
			(start -0.508 -0.9398)
			(end 0.508 -0.9398)
			(stroke
				(width 0.1524)
				(type default)
			)
			(layer "B.SilkS")
		)
		(fp_rect
			(start 0.508 0.9398)
			(end -0.508 -0.9398)
			(stroke
				(width 0)
				(type default)
			)
			(fill no)
			(layer "B.CrtYd")
		)
		(fp_rect
			(start 0.508 0.9398)
			(end -0.508 -0.9398)
			(stroke
				(width 0)
				(type default)
			)
			(fill no)
			(layer "B.Fab")
		)
		(pad "1" smd custom
			(at 0 -0.4445)
			(size 0.1397 0.1397)
			(layers "B.Cu" "B.Mask" "B.Paste")
			(net "BMC_SPI_MOSI_R")
			(options
				(clearance outline)
				(anchor circle)
			)
			(primitives
				(gr_poly
					(pts
						(arc
							(start -0.1778 0.2794)
							(mid -0.249642 0.249642)
							(end -0.2794 0.1778)
						)
						(arc
							(start -0.2794 -0.1778)
							(mid -0.249642 -0.249642)
							(end -0.1778 -0.2794)
						)
						(arc
							(start 0.1778 -0.2794)
							(mid 0.249642 -0.249642)
							(end 0.2794 -0.1778)
						)
						(arc
							(start 0.2794 0.1778)
							(mid 0.249642 0.249642)
							(end 0.1778 0.2794)
						)
					)
					(width 0)
					(fill yes)
				)
			)
		)
		(pad "2" smd custom
			(at 0 0.4445)
			(size 0.1397 0.1397)
			(layers "B.Cu" "B.Mask" "B.Paste")
			(net "BMC_SPI_MOSI")
			(options
				(clearance outline)
				(anchor circle)
			)
			(primitives
				(gr_poly
					(pts
						(arc
							(start -0.1778 0.2794)
							(mid -0.249642 0.249642)
							(end -0.2794 0.1778)
						)
						(arc
							(start -0.2794 -0.1778)
							(mid -0.249642 -0.249642)
							(end -0.1778 -0.2794)
						)
						(arc
							(start 0.1778 -0.2794)
							(mid 0.249642 -0.249642)
							(end 0.2794 -0.1778)
						)
						(arc
							(start 0.2794 0.1778)
							(mid 0.249642 0.249642)
							(end 0.1778 0.2794)
						)
					)
					(width 0)
					(fill yes)
				)
			)
		)
	)
	(footprint ""
		(layer "B.Cu")
		(at 39.457122 -154.728672)
		(property "Reference" "TP64"
			(at 0 0 0)
			(layer "B.SilkS")
			(hide yes)
			(effects
				(font
					(size 1.27 1.27)
				)
				(justify mirror)
			)
		)
		(property "Value" "TPAD28-2-GP"
			(at 0.0127 -1.6637 0)
			(unlocked yes)
			(layer "B.Fab")
			(hide yes)
			(effects
				(font
					(size 1.016 1.016)
					(thickness 0.1524)
				)
				(justify mirror)
			)
		)
		(property "Device Type" "TPAD28"
			(at 0.0127 -3.1877 0)
			(unlocked yes)
			(layer "B.Fab")
			(hide yes)
			(effects
				(font
					(size 1.016 1.016)
					(thickness 0.1524)
				)
				(justify mirror)
			)
		)
		(duplicate_pad_numbers_are_jumpers no)
		(fp_poly
			(pts
				(arc
					(start 0.3556 0)
					(mid -0.3556 0)
					(end 0.3556 0)
				)
			)
			(stroke
				(width 0)
				(type default)
			)
			(fill no)
			(layer "B.CrtYd")
		)
		(fp_poly
			(pts
				(arc
					(start 0.6096 0)
					(mid -0.6096 0)
					(end 0.6096 0)
				)
			)
			(stroke
				(width 0)
				(type default)
			)
			(fill no)
			(layer "B.Fab")
		)
		(pad "1" smd circle
			(at 0 0 180)
			(size 0.7112 0.7112)
			(layers "B.Cu" "B.Mask" "B.Paste")
			(net "TP_BMC_GPION4")
		)
	)
)
